(kicad_pcb
	(version 20260206)
	(generator "pcbnew")
	(generator_version "10.0")
	(general
		(thickness 1.6)
		(legacy_teardrops no)
	)
	(paper "A4")
	(title_block
		(title "03242023_DA0F0TMBIJ0_F0T_Motherboard_J_brd_V01_OCP.brd")
		(comment 1 "Grand Teton / footprints 1893-1899 of 6105")
	)
	(layers
		(0 "F.Cu" signal "TOP")
		(4 "In1.Cu" signal "GND")
		(6 "In2.Cu" signal "IN1")
		(8 "In3.Cu" signal "GND1")
		(10 "In4.Cu" signal "IN2")
		(12 "In5.Cu" signal "GND2")
		(14 "In6.Cu" signal "IN3")
		(16 "In7.Cu" signal "GND3")
		(18 "In8.Cu" signal "VCC")
		(20 "In9.Cu" signal "VCC1")
		(22 "In10.Cu" signal "GND4")
		(24 "In11.Cu" signal "IN4")
		(26 "In12.Cu" signal "GND5")
		(28 "In13.Cu" signal "IN5")
		(30 "In14.Cu" signal "GND6")
		(32 "In15.Cu" signal "IN6")
		(34 "In16.Cu" signal "GND7")
		(2 "B.Cu" signal "BOTTOM")
		(9 "F.Adhes" user "F.Adhesive")
		(11 "B.Adhes" user "B.Adhesive")
		(13 "F.Paste" user "Package Geometry/Pastemask Top")
		(15 "B.Paste" user "Package Geometry/Pastemask Bottom")
		(5 "F.SilkS" user "Ref Des/Silkscreen Top")
		(7 "B.SilkS" user "Ref Des/Silkscreen Bottom")
		(1 "F.Mask" user "Board Geometry/Soldermask Top")
		(3 "B.Mask" user "Board Geometry/Soldermask Bottom")
		(17 "Dwgs.User" user "User.Drawings")
		(19 "Cmts.User" user "User.Comments")
		(21 "Eco1.User" user "User.Eco1")
		(23 "Eco2.User" user "User.Eco2")
		(25 "Edge.Cuts" user "Board Geometry/Outline")
		(27 "Margin" user)
		(31 "F.CrtYd" user "Package Geometry/Place Bound Top")
		(29 "B.CrtYd" user "Package Geometry/Place Bound Bottom")
		(35 "F.Fab" user "Ref Des/Assembly Top")
		(33 "B.Fab" user "Ref Des/Assembly Bottom")
	)
	(footprint ""
		(layer "F.Cu")
		(at 7.42188 -59.019948 180)
		(property "Reference" "R582"
			(at 0 0 180)
			(layer "F.SilkS")
			(hide yes)
			(effects
				(font
					(size 1.27 1.27)
				)
			)
		)
		(property "Value" ""
			(at 0 0 180)
			(layer "F.Fab")
			(effects
				(font
					(size 1.27 1.27)
				)
			)
		)
		(duplicate_pad_numbers_are_jumpers no)
		(fp_line
			(start 0.7874 0.4064)
			(end -0.7874 0.4064)
			(stroke
				(width 0.1524)
				(type default)
			)
			(layer "F.SilkS")
		)
		(fp_line
			(start 0.7874 -0.4064)
			(end 0.7874 0.4064)
			(stroke
				(width 0.1524)
				(type default)
			)
			(layer "F.SilkS")
		)
		(fp_line
			(start -0.7874 0.4064)
			(end -0.7874 -0.4064)
			(stroke
				(width 0.1524)
				(type default)
			)
			(layer "F.SilkS")
		)
		(fp_line
			(start -0.7874 -0.4064)
			(end 0.7874 -0.4064)
			(stroke
				(width 0.1524)
				(type default)
			)
			(layer "F.SilkS")
		)
		(fp_line
			(start 0.67945 0.3048)
			(end 0.120396 0.3048)
			(stroke
				(width 0.1)
				(type default)
			)
			(layer "F.Fab")
		)
		(fp_line
			(start 0.67945 -0.3048)
			(end 0.67945 0.3048)
			(stroke
				(width 0.1)
				(type default)
			)
			(layer "F.Fab")
		)
		(fp_line
			(start 0.12065 -0.2794)
			(end 0.12065 -0.3048)
			(stroke
				(width 0.1)
				(type default)
			)
			(layer "F.Fab")
		)
		(fp_line
			(start 0.12065 -0.3048)
			(end 0.67945 -0.3048)
			(stroke
				(width 0.1)
				(type default)
			)
			(layer "F.Fab")
		)
		(fp_line
			(start 0.120396 0.3048)
			(end 0.120396 0.2794)
			(stroke
				(width 0.1)
				(type default)
			)
			(layer "F.Fab")
		)
		(fp_line
			(start 0.120396 0.2794)
			(end -0.12065 0.2794)
			(stroke
				(width 0.1)
				(type default)
			)
			(layer "F.Fab")
		)
		(fp_line
			(start -0.12065 0.3048)
			(end -0.67945 0.3048)
			(stroke
				(width 0.1)
				(type default)
			)
			(layer "F.Fab")
		)
		(fp_line
			(start -0.12065 0.2794)
			(end -0.12065 0.3048)
			(stroke
				(width 0.1)
				(type default)
			)
			(layer "F.Fab")
		)
		(fp_line
			(start -0.12065 -0.2794)
			(end 0.12065 -0.2794)
			(stroke
				(width 0.1)
				(type default)
			)
			(layer "F.Fab")
		)
		(fp_line
			(start -0.12065 -0.305054)
			(end -0.12065 -0.2794)
			(stroke
				(width 0.1)
				(type default)
			)
			(layer "F.Fab")
		)
		(fp_line
			(start -0.67945 0.3048)
			(end -0.67945 -0.305054)
			(stroke
				(width 0.1)
				(type default)
			)
			(layer "F.Fab")
		)
		(fp_line
			(start -0.67945 -0.305054)
			(end -0.12065 -0.305054)
			(stroke
				(width 0.1)
				(type default)
			)
			(layer "F.Fab")
		)
		(pad "1" smd circle
			(at -0.40005 0 180)
			(size 0 0)
			(layers "F.Cu" "F.Mask" "F.Paste")
			(net "SMB_SML0_3V3AUX_SDA")
		)
		(pad "2" smd circle
			(at 0.40005 0 180)
			(size 0 0)
			(layers "F.Cu" "F.Mask" "F.Paste")
			(net "SMB_SML0_3V3AUX_PCH_SDA")
		)
	)
	(footprint ""
		(layer "F.Cu")
		(at 162.622484 -53.267864 90)
		(property "Reference" "R3634"
			(at 0 0 90)
			(layer "F.SilkS")
			(hide yes)
			(effects
				(font
					(size 1.27 1.27)
				)
			)
		)
		(property "Value" ""
			(at 0 0 90)
			(layer "F.Fab")
			(effects
				(font
					(size 1.27 1.27)
				)
			)
		)
		(duplicate_pad_numbers_are_jumpers no)
		(fp_line
			(start 4.0386 -1.7526)
			(end 4.0386 1.7526)
			(stroke
				(width 0.1524)
				(type default)
			)
			(layer "F.SilkS")
		)
		(fp_line
			(start -4.0386 -1.7526)
			(end 4.0386 -1.7526)
			(stroke
				(width 0.1524)
				(type default)
			)
			(layer "F.SilkS")
		)
		(fp_line
			(start 4.0386 1.7526)
			(end -4.0386 1.7526)
			(stroke
				(width 0.1524)
				(type default)
			)
			(layer "F.SilkS")
		)
		(fp_line
			(start -4.0386 1.7526)
			(end -4.0386 -1.7526)
			(stroke
				(width 0.1524)
				(type default)
			)
			(layer "F.SilkS")
		)
		(fp_line
			(start 4.0386 -1.7526)
			(end 4.0386 1.7526)
			(stroke
				(width 0.1)
				(type default)
			)
			(layer "F.Fab")
		)
		(fp_line
			(start -4.0386 -1.7526)
			(end 4.0386 -1.7526)
			(stroke
				(width 0.1)
				(type default)
			)
			(layer "F.Fab")
		)
		(fp_line
			(start 4.0386 1.7526)
			(end -4.0386 1.7526)
			(stroke
				(width 0.1)
				(type default)
			)
			(layer "F.Fab")
		)
		(fp_line
			(start -4.0386 1.7526)
			(end -4.0386 -1.7526)
			(stroke
				(width 0.1)
				(type default)
			)
			(layer "F.Fab")
		)
		(pad "1" smd rect
			(at -3.1115 0 90)
			(size 1.524 3.2004)
			(layers "F.Cu" "F.Mask" "F.Paste")
			(net "P3V3_M2_0")
		)
		(pad "2" smd rect
			(at 3.1115 0 90)
			(size 1.524 3.2004)
			(layers "F.Cu" "F.Mask" "F.Paste")
			(net "P3V3")
		)
	)
	(footprint ""
		(layer "F.Cu")
		(at 300.728634 -16.715994)
		(property "Reference" "R4205"
			(at 0 0 0)
			(layer "F.SilkS")
			(hide yes)
			(effects
				(font
					(size 1.27 1.27)
				)
			)
		)
		(property "Value" ""
			(at 0 0 0)
			(layer "F.Fab")
			(effects
				(font
					(size 1.27 1.27)
				)
			)
		)
		(duplicate_pad_numbers_are_jumpers no)
		(fp_line
			(start -0.7874 -0.4064)
			(end 0.7874 -0.4064)
			(stroke
				(width 0.1524)
				(type default)
			)
			(layer "F.SilkS")
		)
		(fp_line
			(start -0.7874 0.4064)
			(end -0.7874 -0.4064)
			(stroke
				(width 0.1524)
				(type default)
			)
			(layer "F.SilkS")
		)
		(fp_line
			(start 0.7874 -0.4064)
			(end 0.7874 0.4064)
			(stroke
				(width 0.1524)
				(type default)
			)
			(layer "F.SilkS")
		)
		(fp_line
			(start 0.7874 0.4064)
			(end -0.7874 0.4064)
			(stroke
				(width 0.1524)
				(type default)
			)
			(layer "F.SilkS")
		)
		(fp_line
			(start -0.67945 -0.305054)
			(end -0.12065 -0.305054)
			(stroke
				(width 0.1)
				(type default)
			)
			(layer "F.Fab")
		)
		(fp_line
			(start -0.67945 0.3048)
			(end -0.67945 -0.305054)
			(stroke
				(width 0.1)
				(type default)
			)
			(layer "F.Fab")
		)
		(fp_line
			(start -0.12065 -0.305054)
			(end -0.12065 -0.2794)
			(stroke
				(width 0.1)
				(type default)
			)
			(layer "F.Fab")
		)
		(fp_line
			(start -0.12065 -0.2794)
			(end 0.12065 -0.2794)
			(stroke
				(width 0.1)
				(type default)
			)
			(layer "F.Fab")
		)
		(fp_line
			(start -0.12065 0.2794)
			(end -0.12065 0.3048)
			(stroke
				(width 0.1)
				(type default)
			)
			(layer "F.Fab")
		)
		(fp_line
			(start -0.12065 0.3048)
			(end -0.67945 0.3048)
			(stroke
				(width 0.1)
				(type default)
			)
			(layer "F.Fab")
		)
		(fp_line
			(start 0.120396 0.2794)
			(end -0.12065 0.2794)
			(stroke
				(width 0.1)
				(type default)
			)
			(layer "F.Fab")
		)
		(fp_line
			(start 0.120396 0.3048)
			(end 0.120396 0.2794)
			(stroke
				(width 0.1)
				(type default)
			)
			(layer "F.Fab")
		)
		(fp_line
			(start 0.12065 -0.3048)
			(end 0.67945 -0.3048)
			(stroke
				(width 0.1)
				(type default)
			)
			(layer "F.Fab")
		)
		(fp_line
			(start 0.12065 -0.2794)
			(end 0.12065 -0.3048)
			(stroke
				(width 0.1)
				(type default)
			)
			(layer "F.Fab")
		)
		(fp_line
			(start 0.67945 -0.3048)
			(end 0.67945 0.3048)
			(stroke
				(width 0.1)
				(type default)
			)
			(layer "F.Fab")
		)
		(fp_line
			(start 0.67945 0.3048)
			(end 0.120396 0.3048)
			(stroke
				(width 0.1)
				(type default)
			)
			(layer "F.Fab")
		)
		(pad "1" smd circle
			(at -0.40005 0)
			(size 0 0)
			(layers "F.Cu" "F.Mask" "F.Paste")
			(net "U271_1_ADD0")
		)
		(pad "2" smd circle
			(at 0.40005 0)
			(size 0 0)
			(layers "F.Cu" "F.Mask" "F.Paste")
			(net "GND")
		)
	)
	(footprint ""
		(layer "F.Cu")
		(at 160.760918 -22.361906 180)
		(property "Reference" "R4152"
			(at 0 0 180)
			(layer "F.SilkS")
			(hide yes)
			(effects
				(font
					(size 1.27 1.27)
				)
			)
		)
		(property "Value" ""
			(at 0 0 180)
			(layer "F.Fab")
			(effects
				(font
					(size 1.27 1.27)
				)
			)
		)
		(duplicate_pad_numbers_are_jumpers no)
		(fp_line
			(start 0.7874 0.4064)
			(end -0.7874 0.4064)
			(stroke
				(width 0.1524)
				(type default)
			)
			(layer "F.SilkS")
		)
		(fp_line
			(start 0.7874 -0.4064)
			(end 0.7874 0.4064)
			(stroke
				(width 0.1524)
				(type default)
			)
			(layer "F.SilkS")
		)
		(fp_line
			(start -0.7874 0.4064)
			(end -0.7874 -0.4064)
			(stroke
				(width 0.1524)
				(type default)
			)
			(layer "F.SilkS")
		)
		(fp_line
			(start -0.7874 -0.4064)
			(end 0.7874 -0.4064)
			(stroke
				(width 0.1524)
				(type default)
			)
			(layer "F.SilkS")
		)
		(fp_line
			(start 0.67945 0.3048)
			(end 0.120396 0.3048)
			(stroke
				(width 0.1)
				(type default)
			)
			(layer "F.Fab")
		)
		(fp_line
			(start 0.67945 -0.3048)
			(end 0.67945 0.3048)
			(stroke
				(width 0.1)
				(type default)
			)
			(layer "F.Fab")
		)
		(fp_line
			(start 0.12065 -0.2794)
			(end 0.12065 -0.3048)
			(stroke
				(width 0.1)
				(type default)
			)
			(layer "F.Fab")
		)
		(fp_line
			(start 0.12065 -0.3048)
			(end 0.67945 -0.3048)
			(stroke
				(width 0.1)
				(type default)
			)
			(layer "F.Fab")
		)
		(fp_line
			(start 0.120396 0.3048)
			(end 0.120396 0.2794)
			(stroke
				(width 0.1)
				(type default)
			)
			(layer "F.Fab")
		)
		(fp_line
			(start 0.120396 0.2794)
			(end -0.12065 0.2794)
			(stroke
				(width 0.1)
				(type default)
			)
			(layer "F.Fab")
		)
		(fp_line
			(start -0.12065 0.3048)
			(end -0.67945 0.3048)
			(stroke
				(width 0.1)
				(type default)
			)
			(layer "F.Fab")
		)
		(fp_line
			(start -0.12065 0.2794)
			(end -0.12065 0.3048)
			(stroke
				(width 0.1)
				(type default)
			)
			(layer "F.Fab")
		)
		(fp_line
			(start -0.12065 -0.2794)
			(end 0.12065 -0.2794)
			(stroke
				(width 0.1)
				(type default)
			)
			(layer "F.Fab")
		)
		(fp_line
			(start -0.12065 -0.305054)
			(end -0.12065 -0.2794)
			(stroke
				(width 0.1)
				(type default)
			)
			(layer "F.Fab")
		)
		(fp_line
			(start -0.67945 0.3048)
			(end -0.67945 -0.305054)
			(stroke
				(width 0.1)
				(type default)
			)
			(layer "F.Fab")
		)
		(fp_line
			(start -0.67945 -0.305054)
			(end -0.12065 -0.305054)
			(stroke
				(width 0.1)
				(type default)
			)
			(layer "F.Fab")
		)
		(pad "1" smd circle
			(at -0.40005 0 180)
			(size 0 0)
			(layers "F.Cu" "F.Mask" "F.Paste")
			(net "SMB_1_PLD_3V3AUX_SDA")
		)
		(pad "2" smd circle
			(at 0.40005 0 180)
			(size 0 0)
			(layers "F.Cu" "F.Mask" "F.Paste")
			(net "SMB_2_PLD_3V3AUX_SDA_R1")
		)
	)
	(footprint ""
		(layer "F.Cu")
		(at 386.499354 -347.520514 90)
		(property "Reference" "PR1772"
			(at 0 0 90)
			(layer "F.SilkS")
			(hide yes)
			(effects
				(font
					(size 1.27 1.27)
				)
			)
		)
		(property "Value" ""
			(at 0 0 90)
			(layer "F.Fab")
			(effects
				(font
					(size 1.27 1.27)
				)
			)
		)
		(duplicate_pad_numbers_are_jumpers no)
		(fp_line
			(start 0.7874 -0.4064)
			(end 0.7874 0.4064)
			(stroke
				(width 0.1524)
				(type default)
			)
			(layer "F.SilkS")
		)
		(fp_line
			(start -0.7874 -0.4064)
			(end 0.7874 -0.4064)
			(stroke
				(width 0.1524)
				(type default)
			)
			(layer "F.SilkS")
		)
		(fp_line
			(start 0.7874 0.4064)
			(end -0.7874 0.4064)
			(stroke
				(width 0.1524)
				(type default)
			)
			(layer "F.SilkS")
		)
		(fp_line
			(start -0.7874 0.4064)
			(end -0.7874 -0.4064)
			(stroke
				(width 0.1524)
				(type default)
			)
			(layer "F.SilkS")
		)
		(fp_line
			(start -0.12065 -0.305054)
			(end -0.12065 -0.2794)
			(stroke
				(width 0.1)
				(type default)
			)
			(layer "F.Fab")
		)
		(fp_line
			(start -0.67945 -0.305054)
			(end -0.12065 -0.305054)
			(stroke
				(width 0.1)
				(type default)
			)
			(layer "F.Fab")
		)
		(fp_line
			(start 0.67945 -0.3048)
			(end 0.67945 0.3048)
			(stroke
				(width 0.1)
				(type default)
			)
			(layer "F.Fab")
		)
		(fp_line
			(start 0.12065 -0.3048)
			(end 0.67945 -0.3048)
			(stroke
				(width 0.1)
				(type default)
			)
			(layer "F.Fab")
		)
		(fp_line
			(start 0.12065 -0.2794)
			(end 0.12065 -0.3048)
			(stroke
				(width 0.1)
				(type default)
			)
			(layer "F.Fab")
		)
		(fp_line
			(start -0.12065 -0.2794)
			(end 0.12065 -0.2794)
			(stroke
				(width 0.1)
				(type default)
			)
			(layer "F.Fab")
		)
		(fp_line
			(start 0.120396 0.2794)
			(end -0.12065 0.2794)
			(stroke
				(width 0.1)
				(type default)
			)
			(layer "F.Fab")
		)
		(fp_line
			(start -0.12065 0.2794)
			(end -0.12065 0.3048)
			(stroke
				(width 0.1)
				(type default)
			)
			(layer "F.Fab")
		)
		(fp_line
			(start 0.67945 0.3048)
			(end 0.120396 0.3048)
			(stroke
				(width 0.1)
				(type default)
			)
			(layer "F.Fab")
		)
		(fp_line
			(start 0.120396 0.3048)
			(end 0.120396 0.2794)
			(stroke
				(width 0.1)
				(type default)
			)
			(layer "F.Fab")
		)
		(fp_line
			(start -0.12065 0.3048)
			(end -0.67945 0.3048)
			(stroke
				(width 0.1)
				(type default)
			)
			(layer "F.Fab")
		)
		(fp_line
			(start -0.67945 0.3048)
			(end -0.67945 -0.305054)
			(stroke
				(width 0.1)
				(type default)
			)
			(layer "F.Fab")
		)
		(pad "1" smd circle
			(at -0.40005 0 90)
			(size 0 0)
			(layers "F.Cu" "F.Mask" "F.Paste")
			(net "SW_PVCCIN_CPU0_BOOT8")
		)
		(pad "2" smd circle
			(at 0.40005 0 90)
			(size 0 0)
			(layers "F.Cu" "F.Mask" "F.Paste")
			(net "SW_PVCCIN_CPU0_BOOT8_R")
		)
	)
	(footprint ""
		(layer "F.Cu")
		(at 409.573984 -17.612614 90)
		(property "Reference" "C852"
			(at 0 0 90)
			(layer "F.SilkS")
			(hide yes)
			(effects
				(font
					(size 1.27 1.27)
				)
			)
		)
		(property "Value" ""
			(at 0 0 90)
			(layer "F.Fab")
			(effects
				(font
					(size 1.27 1.27)
				)
			)
		)
		(duplicate_pad_numbers_are_jumpers no)
		(fp_line
			(start 0.299974 -0.150114)
			(end 0.299974 0.150114)
			(stroke
				(width 0.1)
				(type default)
			)
			(layer "F.Fab")
		)
		(fp_line
			(start -0.299974 -0.150114)
			(end 0.299974 -0.150114)
			(stroke
				(width 0.1)
				(type default)
			)
			(layer "F.Fab")
		)
		(fp_line
			(start 0.299974 0.150114)
			(end -0.299974 0.150114)
			(stroke
				(width 0.1)
				(type default)
			)
			(layer "F.Fab")
		)
		(fp_line
			(start -0.299974 0.150114)
			(end -0.299974 -0.150114)
			(stroke
				(width 0.1)
				(type default)
			)
			(layer "F.Fab")
		)
		(pad "1" smd rect
			(at -0.2667 0 90)
			(size 0.3048 0.381)
			(layers "F.Cu" "F.Mask" "F.Paste")
			(net "P5E_CPU0_PE1_TX_C_DN<8>")
		)
		(pad "2" smd rect
			(at 0.2667 0 90)
			(size 0.3048 0.381)
			(layers "F.Cu" "F.Mask" "F.Paste")
			(net "P5E_CPU0_PE1_TX_DN<8>")
		)
	)
	(footprint ""
		(layer "F.Cu")
		(at 96.57588 -53.050948 180)
		(property "Reference" "R1348"
			(at 0 0 180)
			(layer "F.SilkS")
			(hide yes)
			(effects
				(font
					(size 1.27 1.27)
				)
			)
		)
		(property "Value" ""
			(at 0 0 180)
			(layer "F.Fab")
			(effects
				(font
					(size 1.27 1.27)
				)
			)
		)
		(duplicate_pad_numbers_are_jumpers no)
		(fp_line
			(start 0.7874 0.4064)
			(end -0.7874 0.4064)
			(stroke
				(width 0.1524)
				(type default)
			)
			(layer "F.SilkS")
		)
		(fp_line
			(start 0.7874 -0.4064)
			(end 0.7874 0.4064)
			(stroke
				(width 0.1524)
				(type default)
			)
			(layer "F.SilkS")
		)
		(fp_line
			(start -0.7874 0.4064)
			(end -0.7874 -0.4064)
			(stroke
				(width 0.1524)
				(type default)
			)
			(layer "F.SilkS")
		)
		(fp_line
			(start -0.7874 -0.4064)
			(end 0.7874 -0.4064)
			(stroke
				(width 0.1524)
				(type default)
			)
			(layer "F.SilkS")
		)
		(fp_line
			(start 0.67945 0.3048)
			(end 0.120396 0.3048)
			(stroke
				(width 0.1)
				(type default)
			)
			(layer "F.Fab")
		)
		(fp_line
			(start 0.67945 -0.3048)
			(end 0.67945 0.3048)
			(stroke
				(width 0.1)
				(type default)
			)
			(layer "F.Fab")
		)
		(fp_line
			(start 0.12065 -0.2794)
			(end 0.12065 -0.3048)
			(stroke
				(width 0.1)
				(type default)
			)
			(layer "F.Fab")
		)
		(fp_line
			(start 0.12065 -0.3048)
			(end 0.67945 -0.3048)
			(stroke
				(width 0.1)
				(type default)
			)
			(layer "F.Fab")
		)
		(fp_line
			(start 0.120396 0.3048)
			(end 0.120396 0.2794)
			(stroke
				(width 0.1)
				(type default)
			)
			(layer "F.Fab")
		)
		(fp_line
			(start 0.120396 0.2794)
			(end -0.12065 0.2794)
			(stroke
				(width 0.1)
				(type default)
			)
			(layer "F.Fab")
		)
		(fp_line
			(start -0.12065 0.3048)
			(end -0.67945 0.3048)
			(stroke
				(width 0.1)
				(type default)
			)
			(layer "F.Fab")
		)
		(fp_line
			(start -0.12065 0.2794)
			(end -0.12065 0.3048)
			(stroke
				(width 0.1)
				(type default)
			)
			(layer "F.Fab")
		)
		(fp_line
			(start -0.12065 -0.2794)
			(end 0.12065 -0.2794)
			(stroke
				(width 0.1)
				(type default)
			)
			(layer "F.Fab")
		)
		(fp_line
			(start -0.12065 -0.305054)
			(end -0.12065 -0.2794)
			(stroke
				(width 0.1)
				(type default)
			)
			(layer "F.Fab")
		)
		(fp_line
			(start -0.67945 0.3048)
			(end -0.67945 -0.305054)
			(stroke
				(width 0.1)
				(type default)
			)
			(layer "F.Fab")
		)
		(fp_line
			(start -0.67945 -0.305054)
			(end -0.12065 -0.305054)
			(stroke
				(width 0.1)
				(type default)
			)
			(layer "F.Fab")
		)
		(pad "1" smd circle
			(at -0.40005 0 180)
			(size 0 0)
			(layers "F.Cu" "F.Mask" "F.Paste")
			(net "JTAG_DBP_CPU_GTL_TCK_R1")
		)
		(pad "2" smd circle
			(at 0.40005 0 180)
			(size 0 0)
			(layers "F.Cu" "F.Mask" "F.Paste")
			(net "JTAG_DBP_CPU_GTL_TCK")
		)
	)
)
